(kicad_pcb
	(version 20260206)
	(generator "pcbnew")
	(generator_version "10.0")
	(general
		(thickness 1.6)
		(legacy_teardrops no)
	)
	(paper "A4")
	(title_block
		(title "04192023_DAF0TMB3IC0_F0TG_MB_C_brd_V02_OCP.brd")
		(comment 1 "Grand Teton / footprints 7821-7825 of 8354")
	)
	(layers
		(0 "F.Cu" signal "TOP")
		(4 "In1.Cu" signal "GND")
		(6 "In2.Cu" signal "IN1")
		(8 "In3.Cu" signal "GND1")
		(10 "In4.Cu" signal "IN2")
		(12 "In5.Cu" signal "GND2")
		(14 "In6.Cu" signal "IN3")
		(16 "In7.Cu" signal "GND3")
		(18 "In8.Cu" signal "VCC")
		(20 "In9.Cu" signal "VCC1")
		(22 "In10.Cu" signal "GND4")
		(24 "In11.Cu" signal "IN4")
		(26 "In12.Cu" signal "GND5")
		(28 "In13.Cu" signal "IN5")
		(30 "In14.Cu" signal "GND6")
		(32 "In15.Cu" signal "IN6")
		(34 "In16.Cu" signal "GND7")
		(2 "B.Cu" signal "BOTTOM")
		(9 "F.Adhes" user "F.Adhesive")
		(11 "B.Adhes" user "B.Adhesive")
		(13 "F.Paste" user "Package Geometry/Pastemask Top")
		(15 "B.Paste" user "Package Geometry/Pastemask Bottom")
		(5 "F.SilkS" user "Ref Des/Silkscreen Top")
		(7 "B.SilkS" user "Ref Des/Silkscreen Bottom")
		(1 "F.Mask" user "Board Geometry/Soldermask Top")
		(3 "B.Mask" user "Board Geometry/Soldermask Bottom")
		(17 "Dwgs.User" user "User.Drawings")
		(19 "Cmts.User" user "User.Comments")
		(21 "Eco1.User" user "User.Eco1")
		(23 "Eco2.User" user "User.Eco2")
		(25 "Edge.Cuts" user "Board Geometry/Outline")
		(27 "Margin" user)
		(31 "F.CrtYd" user "Package Geometry/Place Bound Top")
		(29 "B.CrtYd" user "Package Geometry/Place Bound Bottom")
		(35 "F.Fab" user "Ref Des/Assembly Top")
		(33 "B.Fab" user "Ref Des/Assembly Bottom")
	)
	(footprint ""
		(layer "B.Cu")
		(at 109.150404 -28.70327 -90)
		(property "Reference" "C6096"
			(at 0 0 90)
			(layer "B.SilkS")
			(hide yes)
			(effects
				(font
					(size 1.27 1.27)
				)
				(justify mirror)
			)
		)
		(property "Value" ""
			(at 0 0 90)
			(layer "B.Fab")
			(effects
				(font
					(size 1.27 1.27)
				)
				(justify mirror)
			)
		)
		(duplicate_pad_numbers_are_jumpers no)
		(fp_line
			(start -0.7874 0.4064)
			(end 0.7874 0.4064)
			(stroke
				(width 0.1524)
				(type default)
			)
			(layer "B.SilkS")
		)
		(fp_line
			(start 0.7874 0.4064)
			(end 0.7874 -0.4064)
			(stroke
				(width 0.1524)
				(type default)
			)
			(layer "B.SilkS")
		)
		(fp_line
			(start -0.7874 -0.4064)
			(end -0.7874 0.4064)
			(stroke
				(width 0.1524)
				(type default)
			)
			(layer "B.SilkS")
		)
		(fp_line
			(start 0.7874 -0.4064)
			(end -0.7874 -0.4064)
			(stroke
				(width 0.1524)
				(type default)
			)
			(layer "B.SilkS")
		)
		(fp_line
			(start -0.67945 0.3048)
			(end -0.120396 0.3048)
			(stroke
				(width 0.1)
				(type default)
			)
			(layer "B.Fab")
		)
		(fp_line
			(start -0.120396 0.3048)
			(end -0.120396 0.2794)
			(stroke
				(width 0.1)
				(type default)
			)
			(layer "B.Fab")
		)
		(fp_line
			(start 0.12065 0.3048)
			(end 0.67945 0.3048)
			(stroke
				(width 0.1)
				(type default)
			)
			(layer "B.Fab")
		)
		(fp_line
			(start 0.67945 0.3048)
			(end 0.67945 -0.305054)
			(stroke
				(width 0.1)
				(type default)
			)
			(layer "B.Fab")
		)
		(fp_line
			(start -0.120396 0.2794)
			(end 0.12065 0.2794)
			(stroke
				(width 0.1)
				(type default)
			)
			(layer "B.Fab")
		)
		(fp_line
			(start 0.12065 0.2794)
			(end 0.12065 0.3048)
			(stroke
				(width 0.1)
				(type default)
			)
			(layer "B.Fab")
		)
		(fp_line
			(start -0.12065 -0.2794)
			(end -0.12065 -0.3048)
			(stroke
				(width 0.1)
				(type default)
			)
			(layer "B.Fab")
		)
		(fp_line
			(start 0.12065 -0.2794)
			(end -0.12065 -0.2794)
			(stroke
				(width 0.1)
				(type default)
			)
			(layer "B.Fab")
		)
		(fp_line
			(start -0.67945 -0.3048)
			(end -0.67945 0.3048)
			(stroke
				(width 0.1)
				(type default)
			)
			(layer "B.Fab")
		)
		(fp_line
			(start -0.12065 -0.3048)
			(end -0.67945 -0.3048)
			(stroke
				(width 0.1)
				(type default)
			)
			(layer "B.Fab")
		)
		(fp_line
			(start 0.12065 -0.305054)
			(end 0.12065 -0.2794)
			(stroke
				(width 0.1)
				(type default)
			)
			(layer "B.Fab")
		)
		(fp_line
			(start 0.67945 -0.305054)
			(end 0.12065 -0.305054)
			(stroke
				(width 0.1)
				(type default)
			)
			(layer "B.Fab")
		)
		(pad "1" smd circle
			(at 0.40005 0 90)
			(size 0 0)
			(layers "B.Cu" "B.Mask" "B.Paste")
			(net "P3V3_AUX_CPU0_USB2_AVDD33")
		)
		(pad "2" smd circle
			(at -0.40005 0 90)
			(size 0 0)
			(layers "B.Cu" "B.Mask" "B.Paste")
			(net "GND")
		)
	)
	(footprint ""
		(layer "B.Cu")
		(at 101.38029 -248.479564 180)
		(property "Reference" "C2326"
			(at 0 0 0)
			(layer "B.SilkS")
			(hide yes)
			(effects
				(font
					(size 1.27 1.27)
				)
				(justify mirror)
			)
		)
		(property "Value" ""
			(at 0 0 0)
			(layer "B.Fab")
			(effects
				(font
					(size 1.27 1.27)
				)
				(justify mirror)
			)
		)
		(duplicate_pad_numbers_are_jumpers no)
		(fp_line
			(start 0.7874 0.4064)
			(end 0.7874 -0.4064)
			(stroke
				(width 0.1524)
				(type default)
			)
			(layer "B.SilkS")
		)
		(fp_line
			(start 0.7874 -0.4064)
			(end -0.7874 -0.4064)
			(stroke
				(width 0.1524)
				(type default)
			)
			(layer "B.SilkS")
		)
		(fp_line
			(start -0.7874 0.4064)
			(end 0.7874 0.4064)
			(stroke
				(width 0.1524)
				(type default)
			)
			(layer "B.SilkS")
		)
		(fp_line
			(start -0.7874 -0.4064)
			(end -0.7874 0.4064)
			(stroke
				(width 0.1524)
				(type default)
			)
			(layer "B.SilkS")
		)
		(fp_line
			(start 0.67945 0.3048)
			(end 0.67945 -0.305054)
			(stroke
				(width 0.1)
				(type default)
			)
			(layer "B.Fab")
		)
		(fp_line
			(start 0.67945 -0.305054)
			(end 0.12065 -0.305054)
			(stroke
				(width 0.1)
				(type default)
			)
			(layer "B.Fab")
		)
		(fp_line
			(start 0.12065 0.3048)
			(end 0.67945 0.3048)
			(stroke
				(width 0.1)
				(type default)
			)
			(layer "B.Fab")
		)
		(fp_line
			(start 0.12065 0.2794)
			(end 0.12065 0.3048)
			(stroke
				(width 0.1)
				(type default)
			)
			(layer "B.Fab")
		)
		(fp_line
			(start 0.12065 -0.2794)
			(end -0.12065 -0.2794)
			(stroke
				(width 0.1)
				(type default)
			)
			(layer "B.Fab")
		)
		(fp_line
			(start 0.12065 -0.305054)
			(end 0.12065 -0.2794)
			(stroke
				(width 0.1)
				(type default)
			)
			(layer "B.Fab")
		)
		(fp_line
			(start -0.120396 0.3048)
			(end -0.120396 0.2794)
			(stroke
				(width 0.1)
				(type default)
			)
			(layer "B.Fab")
		)
		(fp_line
			(start -0.120396 0.2794)
			(end 0.12065 0.2794)
			(stroke
				(width 0.1)
				(type default)
			)
			(layer "B.Fab")
		)
		(fp_line
			(start -0.12065 -0.2794)
			(end -0.12065 -0.3048)
			(stroke
				(width 0.1)
				(type default)
			)
			(layer "B.Fab")
		)
		(fp_line
			(start -0.12065 -0.3048)
			(end -0.67945 -0.3048)
			(stroke
				(width 0.1)
				(type default)
			)
			(layer "B.Fab")
		)
		(fp_line
			(start -0.67945 0.3048)
			(end -0.120396 0.3048)
			(stroke
				(width 0.1)
				(type default)
			)
			(layer "B.Fab")
		)
		(fp_line
			(start -0.67945 -0.3048)
			(end -0.67945 0.3048)
			(stroke
				(width 0.1)
				(type default)
			)
			(layer "B.Fab")
		)
		(pad "1" smd circle
			(at 0.40005 0)
			(size 0 0)
			(layers "B.Cu" "B.Mask" "B.Paste")
			(net "PVDDCR_CPU0_P1")
		)
		(pad "2" smd circle
			(at -0.40005 0)
			(size 0 0)
			(layers "B.Cu" "B.Mask" "B.Paste")
			(net "GND")
		)
	)
	(footprint ""
		(layer "B.Cu")
		(at 180.509164 -23.655782 -90)
		(property "Reference" "R3062"
			(at 0 0 90)
			(layer "B.SilkS")
			(hide yes)
			(effects
				(font
					(size 1.27 1.27)
				)
				(justify mirror)
			)
		)
		(property "Value" ""
			(at 0 0 90)
			(layer "B.Fab")
			(effects
				(font
					(size 1.27 1.27)
				)
				(justify mirror)
			)
		)
		(duplicate_pad_numbers_are_jumpers no)
		(fp_line
			(start -0.7874 0.4064)
			(end 0.7874 0.4064)
			(stroke
				(width 0.1524)
				(type default)
			)
			(layer "B.SilkS")
		)
		(fp_line
			(start 0.7874 0.4064)
			(end 0.7874 -0.4064)
			(stroke
				(width 0.1524)
				(type default)
			)
			(layer "B.SilkS")
		)
		(fp_line
			(start -0.7874 -0.4064)
			(end -0.7874 0.4064)
			(stroke
				(width 0.1524)
				(type default)
			)
			(layer "B.SilkS")
		)
		(fp_line
			(start 0.7874 -0.4064)
			(end -0.7874 -0.4064)
			(stroke
				(width 0.1524)
				(type default)
			)
			(layer "B.SilkS")
		)
		(fp_line
			(start -0.67945 0.3048)
			(end -0.120396 0.3048)
			(stroke
				(width 0.1)
				(type default)
			)
			(layer "B.Fab")
		)
		(fp_line
			(start -0.120396 0.3048)
			(end -0.120396 0.2794)
			(stroke
				(width 0.1)
				(type default)
			)
			(layer "B.Fab")
		)
		(fp_line
			(start 0.12065 0.3048)
			(end 0.67945 0.3048)
			(stroke
				(width 0.1)
				(type default)
			)
			(layer "B.Fab")
		)
		(fp_line
			(start 0.67945 0.3048)
			(end 0.67945 -0.305054)
			(stroke
				(width 0.1)
				(type default)
			)
			(layer "B.Fab")
		)
		(fp_line
			(start -0.120396 0.2794)
			(end 0.12065 0.2794)
			(stroke
				(width 0.1)
				(type default)
			)
			(layer "B.Fab")
		)
		(fp_line
			(start 0.12065 0.2794)
			(end 0.12065 0.3048)
			(stroke
				(width 0.1)
				(type default)
			)
			(layer "B.Fab")
		)
		(fp_line
			(start -0.12065 -0.2794)
			(end -0.12065 -0.3048)
			(stroke
				(width 0.1)
				(type default)
			)
			(layer "B.Fab")
		)
		(fp_line
			(start 0.12065 -0.2794)
			(end -0.12065 -0.2794)
			(stroke
				(width 0.1)
				(type default)
			)
			(layer "B.Fab")
		)
		(fp_line
			(start -0.67945 -0.3048)
			(end -0.67945 0.3048)
			(stroke
				(width 0.1)
				(type default)
			)
			(layer "B.Fab")
		)
		(fp_line
			(start -0.12065 -0.3048)
			(end -0.67945 -0.3048)
			(stroke
				(width 0.1)
				(type default)
			)
			(layer "B.Fab")
		)
		(fp_line
			(start 0.12065 -0.305054)
			(end 0.12065 -0.2794)
			(stroke
				(width 0.1)
				(type default)
			)
			(layer "B.Fab")
		)
		(fp_line
			(start 0.67945 -0.305054)
			(end 0.12065 -0.305054)
			(stroke
				(width 0.1)
				(type default)
			)
			(layer "B.Fab")
		)
		(pad "1" smd circle
			(at 0.40005 0 90)
			(size 0 0)
			(layers "B.Cu" "B.Mask" "B.Paste")
			(net "SMB_CPU0_CPU1_APML_SDA")
		)
		(pad "2" smd circle
			(at -0.40005 0 90)
			(size 0 0)
			(layers "B.Cu" "B.Mask" "B.Paste")
			(net "P3V3_AUX")
		)
	)
	(footprint ""
		(layer "B.Cu")
		(at 90.209878 -148.94941 180)
		(property "Reference" "R8171"
			(at 0 0 0)
			(layer "B.SilkS")
			(hide yes)
			(effects
				(font
					(size 1.27 1.27)
				)
				(justify mirror)
			)
		)
		(property "Value" ""
			(at 0 0 0)
			(layer "B.Fab")
			(effects
				(font
					(size 1.27 1.27)
				)
				(justify mirror)
			)
		)
		(duplicate_pad_numbers_are_jumpers no)
		(fp_line
			(start 0.7874 0.4064)
			(end 0.7874 -0.4064)
			(stroke
				(width 0.1524)
				(type default)
			)
			(layer "B.SilkS")
		)
		(fp_line
			(start 0.7874 -0.4064)
			(end -0.7874 -0.4064)
			(stroke
				(width 0.1524)
				(type default)
			)
			(layer "B.SilkS")
		)
		(fp_line
			(start -0.7874 0.4064)
			(end 0.7874 0.4064)
			(stroke
				(width 0.1524)
				(type default)
			)
			(layer "B.SilkS")
		)
		(fp_line
			(start -0.7874 -0.4064)
			(end -0.7874 0.4064)
			(stroke
				(width 0.1524)
				(type default)
			)
			(layer "B.SilkS")
		)
		(fp_line
			(start 0.67945 0.3048)
			(end 0.67945 -0.305054)
			(stroke
				(width 0.1)
				(type default)
			)
			(layer "B.Fab")
		)
		(fp_line
			(start 0.67945 -0.305054)
			(end 0.12065 -0.305054)
			(stroke
				(width 0.1)
				(type default)
			)
			(layer "B.Fab")
		)
		(fp_line
			(start 0.12065 0.3048)
			(end 0.67945 0.3048)
			(stroke
				(width 0.1)
				(type default)
			)
			(layer "B.Fab")
		)
		(fp_line
			(start 0.12065 0.2794)
			(end 0.12065 0.3048)
			(stroke
				(width 0.1)
				(type default)
			)
			(layer "B.Fab")
		)
		(fp_line
			(start 0.12065 -0.2794)
			(end -0.12065 -0.2794)
			(stroke
				(width 0.1)
				(type default)
			)
			(layer "B.Fab")
		)
		(fp_line
			(start 0.12065 -0.305054)
			(end 0.12065 -0.2794)
			(stroke
				(width 0.1)
				(type default)
			)
			(layer "B.Fab")
		)
		(fp_line
			(start -0.120396 0.3048)
			(end -0.120396 0.2794)
			(stroke
				(width 0.1)
				(type default)
			)
			(layer "B.Fab")
		)
		(fp_line
			(start -0.120396 0.2794)
			(end 0.12065 0.2794)
			(stroke
				(width 0.1)
				(type default)
			)
			(layer "B.Fab")
		)
		(fp_line
			(start -0.12065 -0.2794)
			(end -0.12065 -0.3048)
			(stroke
				(width 0.1)
				(type default)
			)
			(layer "B.Fab")
		)
		(fp_line
			(start -0.12065 -0.3048)
			(end -0.67945 -0.3048)
			(stroke
				(width 0.1)
				(type default)
			)
			(layer "B.Fab")
		)
		(fp_line
			(start -0.67945 0.3048)
			(end -0.120396 0.3048)
			(stroke
				(width 0.1)
				(type default)
			)
			(layer "B.Fab")
		)
		(fp_line
			(start -0.67945 -0.3048)
			(end -0.67945 0.3048)
			(stroke
				(width 0.1)
				(type default)
			)
			(layer "B.Fab")
		)
		(pad "1" smd circle
			(at 0.40005 0)
			(size 0 0)
			(layers "B.Cu" "B.Mask" "B.Paste")
			(net "SVID_PVDDCR_CPU0_P1_SVTO")
		)
		(pad "2" smd circle
			(at -0.40005 0)
			(size 0 0)
			(layers "B.Cu" "B.Mask" "B.Paste")
			(net "SVID_PVDDCR_CPU0_P1_SVTO_R")
		)
	)
	(footprint ""
		(layer "B.Cu")
		(at 50.991262 -390.560052 90)
		(property "Reference" "C254"
			(at 0 0 90)
			(layer "B.SilkS")
			(hide yes)
			(effects
				(font
					(size 1.27 1.27)
				)
				(justify mirror)
			)
		)
		(property "Value" ""
			(at 0 0 90)
			(layer "B.Fab")
			(effects
				(font
					(size 1.27 1.27)
				)
				(justify mirror)
			)
		)
		(duplicate_pad_numbers_are_jumpers no)
		(fp_line
			(start 0.7874 -0.4064)
			(end -0.7874 -0.4064)
			(stroke
				(width 0.1524)
				(type default)
			)
			(layer "B.SilkS")
		)
		(fp_line
			(start -0.7874 -0.4064)
			(end -0.7874 0.4064)
			(stroke
				(width 0.1524)
				(type default)
			)
			(layer "B.SilkS")
		)
		(fp_line
			(start 0.7874 0.4064)
			(end 0.7874 -0.4064)
			(stroke
				(width 0.1524)
				(type default)
			)
			(layer "B.SilkS")
		)
		(fp_line
			(start -0.7874 0.4064)
			(end 0.7874 0.4064)
			(stroke
				(width 0.1524)
				(type default)
			)
			(layer "B.SilkS")
		)
		(fp_line
			(start 0.67945 -0.305054)
			(end 0.12065 -0.305054)
			(stroke
				(width 0.1)
				(type default)
			)
			(layer "B.Fab")
		)
		(fp_line
			(start 0.12065 -0.305054)
			(end 0.12065 -0.2794)
			(stroke
				(width 0.1)
				(type default)
			)
			(layer "B.Fab")
		)
		(fp_line
			(start -0.12065 -0.3048)
			(end -0.67945 -0.3048)
			(stroke
				(width 0.1)
				(type default)
			)
			(layer "B.Fab")
		)
		(fp_line
			(start -0.67945 -0.3048)
			(end -0.67945 0.3048)
			(stroke
				(width 0.1)
				(type default)
			)
			(layer "B.Fab")
		)
		(fp_line
			(start 0.12065 -0.2794)
			(end -0.12065 -0.2794)
			(stroke
				(width 0.1)
				(type default)
			)
			(layer "B.Fab")
		)
		(fp_line
			(start -0.12065 -0.2794)
			(end -0.12065 -0.3048)
			(stroke
				(width 0.1)
				(type default)
			)
			(layer "B.Fab")
		)
		(fp_line
			(start 0.12065 0.2794)
			(end 0.12065 0.3048)
			(stroke
				(width 0.1)
				(type default)
			)
			(layer "B.Fab")
		)
		(fp_line
			(start -0.120396 0.2794)
			(end 0.12065 0.2794)
			(stroke
				(width 0.1)
				(type default)
			)
			(layer "B.Fab")
		)
		(fp_line
			(start 0.67945 0.3048)
			(end 0.67945 -0.305054)
			(stroke
				(width 0.1)
				(type default)
			)
			(layer "B.Fab")
		)
		(fp_line
			(start 0.12065 0.3048)
			(end 0.67945 0.3048)
			(stroke
				(width 0.1)
				(type default)
			)
			(layer "B.Fab")
		)
		(fp_line
			(start -0.120396 0.3048)
			(end -0.120396 0.2794)
			(stroke
				(width 0.1)
				(type default)
			)
			(layer "B.Fab")
		)
		(fp_line
			(start -0.67945 0.3048)
			(end -0.120396 0.3048)
			(stroke
				(width 0.1)
				(type default)
			)
			(layer "B.Fab")
		)
		(pad "1" smd circle
			(at 0.40005 0 270)
			(size 0 0)
			(layers "B.Cu" "B.Mask" "B.Paste")
			(net "P0V9_CPU1_RT0_2A")
		)
		(pad "2" smd circle
			(at -0.40005 0 270)
			(size 0 0)
			(layers "B.Cu" "B.Mask" "B.Paste")
			(net "GND")
		)
	)
)
